# S9S_MB_2U (Grand Teton) — schematic netlist excerpt (pin names and nets, part order shuffled) for the footprints in the layout excerpt that follows; sources: Cadence DE-HDL packaged netlist, KiCad conversion of 03242023_DA0F0TMBIJ0_F0T_Motherboard_J_brd_V01_OCP.brd

PC1281  Q_CAP  22UF 16V 20% X6S  pkg C0805  page 300 : A = SW_P12V_PVCCINFAON_CPU1_FLT ; B = GND
R3661  Q_RES  47K 0.1% EMPTY  pkg 0402LF  page 152 : A = GND ; B = RST_USB_HUB_R_N
C979  Q_CAP  10UF 6.3V 20% X6S  pkg C0402  page 74 : A = PVCCIN_CPU0 ; B = GND

(kicad_pcb
	(version 20260206)
	(generator "pcbnew")
	(generator_version "10.0")
	(general
		(thickness 1.6)
		(legacy_teardrops no)
	)
	(paper "A4")
	(title_block
		(title "03242023_DA0F0TMBIJ0_F0T_Motherboard_J_brd_V01_OCP.brd")
		(comment 1 "Grand Teton / footprints 1649-1651 of 6105")
	)
	(layers
		(0 "F.Cu" signal "TOP")
		(4 "In1.Cu" signal "GND")
		(6 "In2.Cu" signal "IN1")
		(8 "In3.Cu" signal "GND1")
		(10 "In4.Cu" signal "IN2")
		(12 "In5.Cu" signal "GND2")
		(14 "In6.Cu" signal "IN3")
		(16 "In7.Cu" signal "GND3")
		(18 "In8.Cu" signal "VCC")
		(20 "In9.Cu" signal "VCC1")
		(22 "In10.Cu" signal "GND4")
		(24 "In11.Cu" signal "IN4")
		(26 "In12.Cu" signal "GND5")
		(28 "In13.Cu" signal "IN5")
		(30 "In14.Cu" signal "GND6")
		(32 "In15.Cu" signal "IN6")
		(34 "In16.Cu" signal "GND7")
		(2 "B.Cu" signal "BOTTOM")
		(9 "F.Adhes" user "F.Adhesive")
		(11 "B.Adhes" user "B.Adhesive")
		(13 "F.Paste" user "Package Geometry/Pastemask Top")
		(15 "B.Paste" user "Package Geometry/Pastemask Bottom")
		(5 "F.SilkS" user "Ref Des/Silkscreen Top")
		(7 "B.SilkS" user "Ref Des/Silkscreen Bottom")
		(1 "F.Mask" user "Board Geometry/Soldermask Top")
		(3 "B.Mask" user "Board Geometry/Soldermask Bottom")
		(17 "Dwgs.User" user "User.Drawings")
		(19 "Cmts.User" user "User.Comments")
		(21 "Eco1.User" user "User.Eco1")
		(23 "Eco2.User" user "User.Eco2")
		(25 "Edge.Cuts" user "Board Geometry/Outline")
		(27 "Margin" user)
		(31 "F.CrtYd" user "Package Geometry/Place Bound Top")
		(29 "B.CrtYd" user "Package Geometry/Place Bound Bottom")
		(35 "F.Fab" user "Ref Des/Assembly Top")
		(33 "B.Fab" user "Ref Des/Assembly Bottom")
	)
	(footprint ""
		(layer "F.Cu")
		(at 10.873486 -92.687648 90)
		(property "Reference" "R3661"
			(at 0 0 90)
			(layer "F.SilkS")
			(hide yes)
			(effects
				(font
					(size 1.27 1.27)
				)
			)
		)
		(property "Value" ""
			(at 0 0 90)
			(layer "F.Fab")
			(effects
				(font
					(size 1.27 1.27)
				)
			)
		)
		(duplicate_pad_numbers_are_jumpers no)
		(fp_line
			(start 0.7874 -0.4064)
			(end 0.7874 0.4064)
			(stroke
				(width 0.1524)
				(type default)
			)
			(layer "F.SilkS")
		)
		(fp_line
			(start -0.7874 -0.4064)
			(end 0.7874 -0.4064)
			(stroke
				(width 0.1524)
				(type default)
			)
			(layer "F.SilkS")
		)
		(fp_line
			(start 0.7874 0.4064)
			(end -0.7874 0.4064)
			(stroke
				(width 0.1524)
				(type default)
			)
			(layer "F.SilkS")
		)
		(fp_line
			(start -0.7874 0.4064)
			(end -0.7874 -0.4064)
			(stroke
				(width 0.1524)
				(type default)
			)
			(layer "F.SilkS")
		)
		(fp_line
			(start -0.12065 -0.305054)
			(end -0.12065 -0.2794)
			(stroke
				(width 0.1)
				(type default)
			)
			(layer "F.Fab")
		)
		(fp_line
			(start -0.67945 -0.305054)
			(end -0.12065 -0.305054)
			(stroke
				(width 0.1)
				(type default)
			)
			(layer "F.Fab")
		)
		(fp_line
			(start 0.67945 -0.3048)
			(end 0.67945 0.3048)
			(stroke
				(width 0.1)
				(type default)
			)
			(layer "F.Fab")
		)
		(fp_line
			(start 0.12065 -0.3048)
			(end 0.67945 -0.3048)
			(stroke
				(width 0.1)
				(type default)
			)
			(layer "F.Fab")
		)
		(fp_line
			(start 0.12065 -0.2794)
			(end 0.12065 -0.3048)
			(stroke
				(width 0.1)
				(type default)
			)
			(layer "F.Fab")
		)
		(fp_line
			(start -0.12065 -0.2794)
			(end 0.12065 -0.2794)
			(stroke
				(width 0.1)
				(type default)
			)
			(layer "F.Fab")
		)
		(fp_line
			(start 0.120396 0.2794)
			(end -0.12065 0.2794)
			(stroke
				(width 0.1)
				(type default)
			)
			(layer "F.Fab")
		)
		(fp_line
			(start -0.12065 0.2794)
			(end -0.12065 0.3048)
			(stroke
				(width 0.1)
				(type default)
			)
			(layer "F.Fab")
		)
		(fp_line
			(start 0.67945 0.3048)
			(end 0.120396 0.3048)
			(stroke
				(width 0.1)
				(type default)
			)
			(layer "F.Fab")
		)
		(fp_line
			(start 0.120396 0.3048)
			(end 0.120396 0.2794)
			(stroke
				(width 0.1)
				(type default)
			)
			(layer "F.Fab")
		)
		(fp_line
			(start -0.12065 0.3048)
			(end -0.67945 0.3048)
			(stroke
				(width 0.1)
				(type default)
			)
			(layer "F.Fab")
		)
		(fp_line
			(start -0.67945 0.3048)
			(end -0.67945 -0.305054)
			(stroke
				(width 0.1)
				(type default)
			)
			(layer "F.Fab")
		)
		(pad "1" smd circle
			(at -0.40005 0 90)
			(size 0 0)
			(layers "F.Cu" "F.Mask" "F.Paste")
			(net "GND")
		)
		(pad "2" smd circle
			(at 0.40005 0 90)
			(size 0 0)
			(layers "F.Cu" "F.Mask" "F.Paste")
			(net "RST_USB_HUB_R_N")
		)
	)
	(footprint ""
		(layer "F.Cu")
		(at 19.37131 -180.522626 90)
		(property "Reference" "PC1281"
			(at 0 0 90)
			(layer "F.SilkS")
			(hide yes)
			(effects
				(font
					(size 1.27 1.27)
				)
			)
		)
		(property "Value" ""
			(at 0 0 90)
			(layer "F.Fab")
			(effects
				(font
					(size 1.27 1.27)
				)
			)
		)
		(duplicate_pad_numbers_are_jumpers no)
		(fp_line
			(start 1.524 -0.762)
			(end 1.524 0.762)
			(stroke
				(width 0.1524)
				(type default)
			)
			(layer "F.SilkS")
		)
		(fp_line
			(start -1.524 -0.762)
			(end 1.524 -0.762)
			(stroke
				(width 0.1524)
				(type default)
			)
			(layer "F.SilkS")
		)
		(fp_line
			(start 1.524 0.762)
			(end -1.524 0.762)
			(stroke
				(width 0.1524)
				(type default)
			)
			(layer "F.SilkS")
		)
		(fp_line
			(start -1.524 0.762)
			(end -1.524 -0.762)
			(stroke
				(width 0.1524)
				(type default)
			)
			(layer "F.SilkS")
		)
		(fp_line
			(start 1.1049 -0.724916)
			(end -1.1049 -0.724916)
			(stroke
				(width 0.1)
				(type default)
			)
			(layer "F.Fab")
		)
		(fp_line
			(start -1.1049 -0.724916)
			(end -1.1049 0.724916)
			(stroke
				(width 0.1)
				(type default)
			)
			(layer "F.Fab")
		)
		(fp_line
			(start 1.1049 0.724916)
			(end 1.1049 -0.724916)
			(stroke
				(width 0.1)
				(type default)
			)
			(layer "F.Fab")
		)
		(fp_line
			(start -1.1049 0.724916)
			(end 1.1049 0.724916)
			(stroke
				(width 0.1)
				(type default)
			)
			(layer "F.Fab")
		)
		(pad "1" smd rect
			(at -0.889 0 270)
			(size 1.016 1.27)
			(layers "F.Cu" "F.Mask" "F.Paste")
			(net "SW_P12V_PVCCINFAON_CPU1_FLT")
		)
		(pad "2" smd rect
			(at 0.889 0 270)
			(size 1.016 1.27)
			(layers "F.Cu" "F.Mask" "F.Paste")
			(net "GND")
		)
	)
	(footprint ""
		(layer "F.Cu")
		(at 355.247448 -247.715024 90)
		(property "Reference" "C979"
			(at 0 0 90)
			(layer "F.SilkS")
			(hide yes)
			(effects
				(font
					(size 1.27 1.27)
				)
			)
		)
		(property "Value" ""
			(at 0 0 90)
			(layer "F.Fab")
			(effects
				(font
					(size 1.27 1.27)
				)
			)
		)
		(duplicate_pad_numbers_are_jumpers no)
		(fp_line
			(start 0.7874 -0.4064)
			(end 0.7874 0.4064)
			(stroke
				(width 0.1524)
				(type default)
			)
			(layer "F.SilkS")
		)
		(fp_line
			(start -0.7874 -0.4064)
			(end 0.7874 -0.4064)
			(stroke
				(width 0.1524)
				(type default)
			)
			(layer "F.SilkS")
		)
		(fp_line
			(start 0.7874 0.4064)
			(end -0.7874 0.4064)
			(stroke
				(width 0.1524)
				(type default)
			)
			(layer "F.SilkS")
		)
		(fp_line
			(start -0.7874 0.4064)
			(end -0.7874 -0.4064)
			(stroke
				(width 0.1524)
				(type default)
			)
			(layer "F.SilkS")
		)
		(fp_line
			(start -0.12065 -0.305054)
			(end -0.12065 -0.2794)
			(stroke
				(width 0.1)
				(type default)
			)
			(layer "F.Fab")
		)
		(fp_line
			(start -0.67945 -0.305054)
			(end -0.12065 -0.305054)
			(stroke
				(width 0.1)
				(type default)
			)
			(layer "F.Fab")
		)
		(fp_line
			(start 0.67945 -0.3048)
			(end 0.67945 0.3048)
			(stroke
				(width 0.1)
				(type default)
			)
			(layer "F.Fab")
		)
		(fp_line
			(start 0.12065 -0.3048)
			(end 0.67945 -0.3048)
			(stroke
				(width 0.1)
				(type default)
			)
			(layer "F.Fab")
		)
		(fp_line
			(start 0.12065 -0.2794)
			(end 0.12065 -0.3048)
			(stroke
				(width 0.1)
				(type default)
			)
			(layer "F.Fab")
		)
		(fp_line
			(start -0.12065 -0.2794)
			(end 0.12065 -0.2794)
			(stroke
				(width 0.1)
				(type default)
			)
			(layer "F.Fab")
		)
		(fp_line
			(start 0.120396 0.2794)
			(end -0.12065 0.2794)
			(stroke
				(width 0.1)
				(type default)
			)
			(layer "F.Fab")
		)
		(fp_line
			(start -0.12065 0.2794)
			(end -0.12065 0.3048)
			(stroke
				(width 0.1)
				(type default)
			)
			(layer "F.Fab")
		)
		(fp_line
			(start 0.67945 0.3048)
			(end 0.120396 0.3048)
			(stroke
				(width 0.1)
				(type default)
			)
			(layer "F.Fab")
		)
		(fp_line
			(start 0.120396 0.3048)
			(end 0.120396 0.2794)
			(stroke
				(width 0.1)
				(type default)
			)
			(layer "F.Fab")
		)
		(fp_line
			(start -0.12065 0.3048)
			(end -0.67945 0.3048)
			(stroke
				(width 0.1)
				(type default)
			)
			(layer "F.Fab")
		)
		(fp_line
			(start -0.67945 0.3048)
			(end -0.67945 -0.305054)
			(stroke
				(width 0.1)
				(type default)
			)
			(layer "F.Fab")
		)
		(pad "1" smd circle
			(at -0.40005 0 90)
			(size 0 0)
			(layers "F.Cu" "F.Mask" "F.Paste")
			(net "PVCCIN_CPU0")
		)
		(pad "2" smd circle
			(at 0.40005 0 90)
			(size 0 0)
			(layers "F.Cu" "F.Mask" "F.Paste")
			(net "GND")
		)
	)
)
